FILE_TYPE = CONNECTIVITY;
{Allegro Design Entry HDL 17.2-2016 S081 (4005846) 1/11/2022}
"PAGE_NUMBER" = 14;
0"NC";
1"P3V3_AUX\g";
2"P1V2_P1V0_I3C_VDDL1\g";
3"P1V8_AUX\g";
4"P1V8_AUX\g";
5"GND\g";
6"GND\g";
7"I3C4_SPD_SDA";
8"I3C4_SPD_SCL";
9"I3C3_SPD_SDA";
10"I3C2_SPD_SDA";
11"I3C2_SPD_SCL";
12"I3C1_SPD_SCL";
13"I3C1_SDA_R";
14"FM_BOARD_BMC_REV_ID1";
15"FM_BOARD_BMC_REV_ID0";
16"I3C4_SPD_SDA";
17"I3C4_SPD_SCL";
18"I3C3_SPD_SDA";
19"I3C3_SPD_SCL";
20"FM_BOARD_BMC_REV_ID2";
21"I3C1_SCL_R";
22"I3C1_SPD_SDA";
23"I3C3_SCL_R";
24"I3C4_SCL_R";
25"I3C4_SDA_R";
26"I3C3_SDA_R";
27"AC_PWR_BMC_BTN_N";
28"I3C2_SPD_SCL";
29"I3C1_SPD_SDA";
30"I3C2_SCL_R";
31"I3C1_SPD_SCL";
32"I3C2_SDA_R";
33"I3C2_SPD_SDA";
34"AC_PWR_BMC_BTN_R_N";
35"I3C3_SPD_SCL";
36"BMC_EMMC_WP_N";
37"BMC_EMMC_CD_N";
%"AST2600A3GP"
"3","(525,3950)","0","pure_quanta","I149";
;
MATERIAL"IC"
PART_TYPE"SMLF"
VALUE"AST2600A3-GP"
PART_NUMBER"AJ026000T06"
NEEDS_NO_SIZE"TRUE"
CDS_LMAN_SYM_OUTLINE"-1025,825,1025,-825"
CDS_LIB"pure_quanta"
LOCATION"U5"
$SEC"3"
CDS_SEC"3";
"I3C4SDA||FSI2DATA"
$PN"AF24"25;
"I3C4SCL||FSI2CLK"
$PN"AE25"24;
"I3C3SDA||FSI1DATA"
$PN"AE26"26;
"I3C3SCL||FSI1CLK"
$PN"AF25"23;
"I3C2SDA"
$PN"AE22"32;
"I3C2SCL"
$PN"AF22"30;
"I3C1SDA"
$PN"AE24"13;
"I3C1SCL"
$PN"AF23"21;
"GPIO18E3||EMMCDAT7||FWSPI18MISO||VBMISO"
$PN"Y4"0;
"GPIO18E2||EMMCDAT6||FWSPI18MOSI||VBMOSI"
$PN"Y3"0;
"GPIO18E1||EMMCDAT5||FWSPI18CK||VBCK"
$PN"Y2"0;
"GPIO18E0||EMMCDAT4||FWSPI18CS#||VBCS#"
$PN"Y1"0;
"GPIO18D7||EMMCWP#"
$PN"AB6"0;
"GPIO18D6||EMMCCD#"
$PN"AC5"0;
"GPIO18D5||EMMCDAT3"
$PN"AB5"0;
"GPIO18D4||EMMCDAT2"
$PN"Y5"0;
"GPIO18D3||EMMCDAT1"
$PN"AA5"0;
"GPIO18D2||EMMCDAT0"
$PN"AC4"0;
"GPIO18D1||EMMCCMD"
$PN"AA4"0;
"GPIO18D0||EMMCCLK"
$PN"AB4"0;
"RGMII2TXD3||GPIO18C1"
$PN"F5"20;
"RGMII2TXD2||GPIO18C0"
$PN"E4"14;
"RGMII2TXD1||RMII2TXD1||GPIO18B7"
$PN"D3"15;
"RGMII2TXD0||RMII2TXD0||GPIO18B6"
$PN"C1"0;
"RGMII2TXCTL||RMII2TXEN||GPIO18B5"
$PN"C2"0;
"RGMII2TXCK||RMII2RCLKO||GPIO18B4"
$PN"D4"0;
"RGMII2RXD3||RMII2RXER||GPIO18C7"
$PN"E1"0;
"RGMII2RXD2||RMII2CRSDV||GPIO18C6"
$PN"E2"0;
"RGMII2RXD1||RMII2RXD1||GPIO18C5"
$PN"F4"0;
"RGMII2RXD0||RMII2RXD0||GPIO18C4"
$PN"D1"0;
"RGMII2RXCTL||GPIO18C3"
$PN"E3"0;
"RGMII2RXCK||RMII2RCLKI||GPIO18C2"
$PN"D2"0;
"RGMII1TXD3||GPIO18A5"
$PN"E6"0;
"RGMII1TXD2||GPIO18A4"
$PN"C5"0;
"RGMII1TXD1||RMII1TXD1||GPIO18A3"
$PN"A3"0;
"RGMII1TXD0||RMII1TXD0||GPIO18A2"
$PN"D5"0;
"RGMII1TXCTL||RMII1TXEN||GPIO18A1"
$PN"D6"0;
"RGMII1TXCK||RMII1RCLKO||GPIO18A0"
$PN"C6"34;
"RGMII1RXD3||RMII1RXER||GPIO18B3"
$PN"E5"0;
"RGMII1RXD2||RMII1CRSDV||GPIO18B2"
$PN"C4"0;
"RGMII1RXD1||RMII1RXD1||GPIO18B1"
$PN"B1"0;
"RGMII1RXD0||RMII1RXD0||GPIO18B0"
$PN"B2"0;
"RGMII1RXCTL||GPIO18A7"
$PN"A2"0;
"RGMII1RXCK||RMII1RCLKI||GPIO18A6"
$PN"B3"0;
%"UNIVERSAL_GND"
"1","(-2975,650)","0","logical_power","I162";
;
CDS_LIB"logical_power"
HDL_POWER"GND";
"A"5;
%"Q_RES"
"2","(-3100,975)","0","pure_quanta","I163";
;
WATTAGE"1/16W"
PACK_TYPE"0402LF"
MATERIAL"EMPTY"
TOLERANCE"1%"
VALUE"1K"
SEC_TYPE"0402LF"
CDS_LIB"pure_quanta"
PART_NUMBER"TMP_QCS21002FB24"
LOCATION"R684"
SEC"1";
"A"
$PN"1"36;
"B"
$PN"2"5;
%"Q_RES"
"2","(-3100,1600)","0","pure_quanta","I164";
;
TOLERANCE"1%"
VALUE"4.7K"
PACK_TYPE"0402LF"
MATERIAL"EMPTY"
WATTAGE"1/16W"
PART_NUMBER"CS24702FB10"
CDS_LIB"pure_quanta"
LOCATION"R686"
$SEC"1"
CDS_SEC"1";
"A"
$PN"1"1;
"B"
$PN"2"36;
%"Q_RES"
"2","(-2875,975)","0","pure_quanta","I165";
;
PACK_TYPE"0402LF"
PART_NUMBER"TMP_QCS21002FB24"
TOLERANCE"1%"
WATTAGE"1/16W"
MATERIAL"EMPTY"
VALUE"1K"
CDS_LIB"pure_quanta"
SEC_TYPE"0402LF"
LOCATION"R685"
SEC"1";
"A"
$PN"1"37;
"B"
$PN"2"5;
%"Q_RES"
"2","(-2875,1600)","0","pure_quanta","I166";
;
PART_NUMBER"CS24702FB10"
PACK_TYPE"0402LF"
TOLERANCE"1%"
WATTAGE"1/16W"
MATERIAL"EMPTY"
VALUE"4.7K"
CDS_LIB"pure_quanta"
LOCATION"R687"
$SEC"1"
CDS_SEC"1";
"A"
$PN"1"1;
"B"
$PN"2"37;
%"Q_RES"
"1","(-275,2200)","0","pure_quanta","I171";
;
PACK_TYPE"0402LF"
VALUE"1K"
WATTAGE"1/16W"
TOLERANCE"1%"
MATERIAL"CHIP"
PART_NUMBER"CS21002FB06"
CDS_LIB"pure_quanta"
LOCATION"R194"
$SEC"1"
CDS_SEC"1";
"B"
$PN"2"12;
"A"
$PN"1"2;
%"Q_RES"
"1","(-275,2100)","0","pure_quanta","I172";
;
TOLERANCE"1%"
MATERIAL"CHIP"
WATTAGE"1/16W"
PACK_TYPE"0402LF"
VALUE"1K"
CDS_LIB"pure_quanta"
PART_NUMBER"CS21002FB06"
LOCATION"R195"
$SEC"1"
CDS_SEC"1";
"B"
$PN"2"29;
"A"
$PN"1"2;
%"Q_RES"
"1","(-275,2000)","0","pure_quanta","I173";
;
PACK_TYPE"0402LF"
MATERIAL"CHIP"
WATTAGE"1/16W"
TOLERANCE"1%"
VALUE"1K"
CDS_LIB"pure_quanta"
PART_NUMBER"CS21002FB06"
LOCATION"R190"
$SEC"1"
CDS_SEC"1";
"B"
$PN"2"11;
"A"
$PN"1"2;
%"Q_RES"
"1","(-275,1900)","0","pure_quanta","I174";
;
PACK_TYPE"0402LF"
MATERIAL"CHIP"
WATTAGE"1/16W"
VALUE"1K"
TOLERANCE"1%"
PART_NUMBER"CS21002FB06"
CDS_LIB"pure_quanta"
LOCATION"R191"
$SEC"1"
CDS_SEC"1";
"B"
$PN"2"10;
"A"
$PN"1"2;
%"Q_RES"
"1","(-275,1800)","0","pure_quanta","I183";
;
MATERIAL"CHIP"
PACK_TYPE"0402LF"
TOLERANCE"1%"
WATTAGE"1/16W"
VALUE"1K"
CDS_LIB"pure_quanta"
PART_NUMBER"CS21002FB06"
LOCATION"R188"
$SEC"1"
CDS_SEC"1";
"B"
$PN"2"35;
"A"
$PN"1"2;
%"Q_RES"
"1","(-275,1700)","0","pure_quanta","I188";
;
MATERIAL"CHIP"
PACK_TYPE"0402LF"
TOLERANCE"1%"
WATTAGE"1/16W"
VALUE"1K"
CDS_LIB"pure_quanta"
PART_NUMBER"CS21002FB06"
LOCATION"R189"
$SEC"1"
CDS_SEC"1";
"B"
$PN"2"9;
"A"
$PN"1"2;
%"Q_RES"
"1","(-275,1575)","0","pure_quanta","I189";
;
MATERIAL"CHIP"
PACK_TYPE"0402LF"
VALUE"1K"
TOLERANCE"1%"
WATTAGE"1/16W"
CDS_LIB"pure_quanta"
PART_NUMBER"CS21002FB06"
LOCATION"R196"
$SEC"1"
CDS_SEC"1";
"B"
$PN"2"8;
"A"
$PN"1"2;
%"Q_RES"
"1","(-275,1475)","0","pure_quanta","I190";
;
MATERIAL"CHIP"
VALUE"1K"
TOLERANCE"1%"
PACK_TYPE"0402LF"
WATTAGE"1/16W"
CDS_LIB"pure_quanta"
PART_NUMBER"CS21002FB06"
LOCATION"R197"
$SEC"1"
CDS_SEC"1";
"B"
$PN"2"7;
"A"
$PN"1"2;
%"UNIVERSAL_GND"
"1","(4850,3525)","0","logical_power","I208";
;
CDS_LIB"logical_power"
HDL_POWER"GND";
"A"6;
%"UNIVERSAL_POWER"
"1","(4850,4625)","0","logical_power","I218";
;
HDL_POWER"P1V8_AUX"
CDS_LIB"logical_power";
"A"4;
%"UNIVERSAL_POWER"
"1","(-2875,2050)","0","logical_power","I219";
;
HDL_POWER"P3V3_AUX"
CDS_LIB"logical_power";
"A"1;
%"Q_RES"
"2","(4625,4350)","0","pure_quanta","I220";
;
VALUE"4.7K"
PACK_TYPE"0402LF"
MATERIAL"CHIP"
TOLERANCE"1%"
WATTAGE"1/16W"
CDS_LIB"pure_quanta"
PART_NUMBER"CS24702FB06"
LOCATION"R856"
$SEC"1"
CDS_SEC"1";
"A"
$PN"1"4;
"B"
$PN"2"14;
%"Q_RES"
"2","(4400,4350)","0","pure_quanta","I221";
;
VALUE"4.7K"
TOLERANCE"1%"
PACK_TYPE"0402LF"
WATTAGE"1/16W"
MATERIAL"EMPTY"
PART_NUMBER"CS24702FB06"
CDS_LIB"pure_quanta"
LOCATION"R854"
$SEC"1"
CDS_SEC"1";
"A"
$PN"1"4;
"B"
$PN"2"20;
%"Q_RES"
"2","(4850,4350)","0","pure_quanta","I222";
;
WATTAGE"1/16W"
TOLERANCE"1%"
PACK_TYPE"0402LF"
MATERIAL"CHIP"
VALUE"4.7K"
CDS_LIB"pure_quanta"
PART_NUMBER"CS24702FB06"
LOCATION"R858"
$SEC"1"
CDS_SEC"1";
"A"
$PN"1"4;
"B"
$PN"2"15;
%"Q_RES"
"2","(4400,3800)","0","pure_quanta","I223";
;
PART_NUMBER"CS21002FB06"
VALUE"1K"
PACK_TYPE"0402LF"
WATTAGE"1/16W"
MATERIAL"CHIP"
TOLERANCE"1%"
CDS_LIB"pure_quanta"
LOCATION"R855"
$SEC"1"
CDS_SEC"1";
"A"
$PN"1"20;
"B"
$PN"2"6;
%"Q_RES"
"2","(4625,3800)","0","pure_quanta","I224";
;
VALUE"1K"
TOLERANCE"1%"
PACK_TYPE"0402LF"
WATTAGE"1/16W"
MATERIAL"EMPTY"
CDS_LIB"pure_quanta"
PART_NUMBER"CS21002FB06"
LOCATION"R857"
$SEC"1"
CDS_SEC"1";
"A"
$PN"1"14;
"B"
$PN"2"6;
%"Q_RES"
"2","(4850,3800)","0","pure_quanta","I225";
;
MATERIAL"EMPTY"
PACK_TYPE"0402LF"
WATTAGE"1/16W"
TOLERANCE"1%"
VALUE"1K"
PART_NUMBER"CS21002FB06"
CDS_LIB"pure_quanta"
LOCATION"R865"
$SEC"1"
CDS_SEC"1";
"A"
$PN"1"15;
"B"
$PN"2"6;
%"Q_RES"
"1","(2800,4675)","0","pure_quanta","I229";
;
VALUE"33.2"
MATERIAL"CHIP"
TOLERANCE"1%"
PART_NUMBER"CS03322FB03"
PACK_TYPE"0402LF"
WATTAGE"1/16W"
CDS_LIB"pure_quanta"
$LOCATION"R884"
CDS_LOCATION"R884"
$SEC"1"
CDS_SEC"1";
"B"
$PN"2"27;
"A"
$PN"1"34;
%"UNIVERSAL_POWER"
"1","(3100,5050)","0","logical_power","I230";
;
HDL_POWER"P1V8_AUX"
CDS_LIB"logical_power";
"A"3;
%"Q_RES"
"2","(3100,4875)","0","pure_quanta","I231";
;
TOLERANCE"1%"
VALUE"4.7K"
MATERIAL"CHIP"
WATTAGE"1/16W"
PACK_TYPE"0402LF"
CDS_LIB"pure_quanta"
PART_NUMBER"CS24702FB06"
$LOCATION"R885"
CDS_LOCATION"R885"
$SEC"1"
CDS_SEC"1";
"A"
$PN"1"3;
"B"
$PN"2"27;
%"Q_RES"
"1","(-2150,3425)","0","pure_quanta","I232";
;
MATERIAL"CHIP"
VALUE"110"
PART_NUMBER"CS11102FB03"
CDS_LIB"pure_quanta"
WATTAGE"1/16W"
TOLERANCE"1%"
PACK_TYPE"0402LF"
LOCATION"R184"
$SEC"1"
CDS_SEC"1";
"B"
$PN"2"21;
"A"
$PN"1"31;
%"Q_RES"
"1","(-2150,3275)","0","pure_quanta","I233";
;
MATERIAL"CHIP"
VALUE"110"
PART_NUMBER"CS11102FB03"
PACK_TYPE"0402LF"
TOLERANCE"1%"
WATTAGE"1/16W"
CDS_LIB"pure_quanta"
LOCATION"R186"
$SEC"1"
CDS_SEC"1";
"B"
$PN"2"30;
"A"
$PN"1"28;
%"Q_RES"
"1","(3100,3425)","0","pure_quanta","I234";
;
PART_NUMBER"CS11102FB03"
VALUE"110"
MATERIAL"CHIP"
PACK_TYPE"0402LF"
TOLERANCE"1%"
WATTAGE"1/16W"
CDS_LIB"pure_quanta"
LOCATION"R198"
$SEC"1"
CDS_SEC"1";
"B"
$PN"2"19;
"A"
$PN"1"23;
%"Q_RES"
"1","(3100,3275)","0","pure_quanta","I235";
;
VALUE"110"
MATERIAL"CHIP"
PART_NUMBER"CS11102FB03"
WATTAGE"1/16W"
TOLERANCE"1%"
PACK_TYPE"0402LF"
CDS_LIB"pure_quanta"
LOCATION"R200"
$SEC"1"
CDS_SEC"1";
"B"
$PN"2"17;
"A"
$PN"1"24;
%"Q_RES"
"1","(-2150,3375)","0","pure_quanta","I236";
;
PACK_TYPE"0402LF"
MATERIAL"CHIP"
VALUE"33.2"
WATTAGE"1/16W"
CDS_LIB"pure_quanta"
TOLERANCE"1%"
PART_NUMBER"CS03322FB03"
LOCATION"R185"
$SEC"1"
CDS_SEC"1";
"B"
$PN"2"13;
"A"
$PN"1"22;
%"Q_RES"
"1","(-2150,3225)","0","pure_quanta","I237";
;
MATERIAL"CHIP"
VALUE"33.2"
PACK_TYPE"0402LF"
CDS_LIB"pure_quanta"
WATTAGE"1/16W"
TOLERANCE"1%"
PART_NUMBER"CS03322FB03"
LOCATION"R187"
$SEC"1"
CDS_SEC"1";
"B"
$PN"2"32;
"A"
$PN"1"33;
%"Q_RES"
"1","(3100,3375)","0","pure_quanta","I238";
;
VALUE"33.2"
MATERIAL"CHIP"
CDS_LIB"pure_quanta"
WATTAGE"1/16W"
TOLERANCE"1%"
PART_NUMBER"CS03322FB03"
PACK_TYPE"0402LF"
LOCATION"R199"
$SEC"1"
CDS_SEC"1";
"B"
$PN"2"18;
"A"
$PN"1"26;
%"Q_RES"
"1","(3100,3225)","0","pure_quanta","I239";
;
MATERIAL"CHIP"
VALUE"33.2"
CDS_LIB"pure_quanta"
WATTAGE"1/16W"
TOLERANCE"1%"
PART_NUMBER"CS03322FB03"
PACK_TYPE"0402LF"
LOCATION"R201"
$SEC"1"
CDS_SEC"1";
"B"
$PN"2"16;
"A"
$PN"1"25;
%"UNIVERSAL_POWER"
"1","(-725,2300)","0","logical_power","I9";
;
HDL_POWER"P1V2_P1V0_I3C_VDDL1"
CDS_LIB"logical_power";
"A"2;
END.
